(kicad_pcb
	(version 20260206)
	(generator "pcbnew")
	(generator_version "10.0")
	(general
		(thickness 1.6)
		(legacy_teardrops no)
	)
	(paper "A4")
	(title_block
		(title "04192023_DAF0TMB3IC0_F0TG_MB_C_brd_V02_OCP.brd")
		(comment 1 "Grand Teton / footprints 1351-1356 of 8354")
	)
	(layers
		(0 "F.Cu" signal "TOP")
		(4 "In1.Cu" signal "GND")
		(6 "In2.Cu" signal "IN1")
		(8 "In3.Cu" signal "GND1")
		(10 "In4.Cu" signal "IN2")
		(12 "In5.Cu" signal "GND2")
		(14 "In6.Cu" signal "IN3")
		(16 "In7.Cu" signal "GND3")
		(18 "In8.Cu" signal "VCC")
		(20 "In9.Cu" signal "VCC1")
		(22 "In10.Cu" signal "GND4")
		(24 "In11.Cu" signal "IN4")
		(26 "In12.Cu" signal "GND5")
		(28 "In13.Cu" signal "IN5")
		(30 "In14.Cu" signal "GND6")
		(32 "In15.Cu" signal "IN6")
		(34 "In16.Cu" signal "GND7")
		(2 "B.Cu" signal "BOTTOM")
		(9 "F.Adhes" user "F.Adhesive")
		(11 "B.Adhes" user "B.Adhesive")
		(13 "F.Paste" user "Package Geometry/Pastemask Top")
		(15 "B.Paste" user "Package Geometry/Pastemask Bottom")
		(5 "F.SilkS" user "Ref Des/Silkscreen Top")
		(7 "B.SilkS" user "Ref Des/Silkscreen Bottom")
		(1 "F.Mask" user "Board Geometry/Soldermask Top")
		(3 "B.Mask" user "Board Geometry/Soldermask Bottom")
		(17 "Dwgs.User" user "User.Drawings")
		(19 "Cmts.User" user "User.Comments")
		(21 "Eco1.User" user "User.Eco1")
		(23 "Eco2.User" user "User.Eco2")
		(25 "Edge.Cuts" user "Board Geometry/Outline")
		(27 "Margin" user)
		(31 "F.CrtYd" user "Package Geometry/Place Bound Top")
		(29 "B.CrtYd" user "Package Geometry/Place Bound Bottom")
		(35 "F.Fab" user "Ref Des/Assembly Top")
		(33 "B.Fab" user "Ref Des/Assembly Bottom")
	)
	(footprint ""
		(layer "F.Cu")
		(at 187.871608 -100.290376 90)
		(property "Reference" "R1339"
			(at 0 0 90)
			(layer "F.SilkS")
			(hide yes)
			(effects
				(font
					(size 1.27 1.27)
				)
			)
		)
		(property "Value" ""
			(at 0 0 90)
			(layer "F.Fab")
			(effects
				(font
					(size 1.27 1.27)
				)
			)
		)
		(duplicate_pad_numbers_are_jumpers no)
		(fp_line
			(start 0.7874 -0.4064)
			(end 0.7874 0.4064)
			(stroke
				(width 0.1524)
				(type default)
			)
			(layer "F.SilkS")
		)
		(fp_line
			(start -0.7874 -0.4064)
			(end 0.7874 -0.4064)
			(stroke
				(width 0.1524)
				(type default)
			)
			(layer "F.SilkS")
		)
		(fp_line
			(start 0.7874 0.4064)
			(end -0.7874 0.4064)
			(stroke
				(width 0.1524)
				(type default)
			)
			(layer "F.SilkS")
		)
		(fp_line
			(start -0.7874 0.4064)
			(end -0.7874 -0.4064)
			(stroke
				(width 0.1524)
				(type default)
			)
			(layer "F.SilkS")
		)
		(fp_line
			(start -0.12065 -0.305054)
			(end -0.12065 -0.2794)
			(stroke
				(width 0.1)
				(type default)
			)
			(layer "F.Fab")
		)
		(fp_line
			(start -0.67945 -0.305054)
			(end -0.12065 -0.305054)
			(stroke
				(width 0.1)
				(type default)
			)
			(layer "F.Fab")
		)
		(fp_line
			(start 0.67945 -0.3048)
			(end 0.67945 0.3048)
			(stroke
				(width 0.1)
				(type default)
			)
			(layer "F.Fab")
		)
		(fp_line
			(start 0.12065 -0.3048)
			(end 0.67945 -0.3048)
			(stroke
				(width 0.1)
				(type default)
			)
			(layer "F.Fab")
		)
		(fp_line
			(start 0.12065 -0.2794)
			(end 0.12065 -0.3048)
			(stroke
				(width 0.1)
				(type default)
			)
			(layer "F.Fab")
		)
		(fp_line
			(start -0.12065 -0.2794)
			(end 0.12065 -0.2794)
			(stroke
				(width 0.1)
				(type default)
			)
			(layer "F.Fab")
		)
		(fp_line
			(start 0.120396 0.2794)
			(end -0.12065 0.2794)
			(stroke
				(width 0.1)
				(type default)
			)
			(layer "F.Fab")
		)
		(fp_line
			(start -0.12065 0.2794)
			(end -0.12065 0.3048)
			(stroke
				(width 0.1)
				(type default)
			)
			(layer "F.Fab")
		)
		(fp_line
			(start 0.67945 0.3048)
			(end 0.120396 0.3048)
			(stroke
				(width 0.1)
				(type default)
			)
			(layer "F.Fab")
		)
		(fp_line
			(start 0.120396 0.3048)
			(end 0.120396 0.2794)
			(stroke
				(width 0.1)
				(type default)
			)
			(layer "F.Fab")
		)
		(fp_line
			(start -0.12065 0.3048)
			(end -0.67945 0.3048)
			(stroke
				(width 0.1)
				(type default)
			)
			(layer "F.Fab")
		)
		(fp_line
			(start -0.67945 0.3048)
			(end -0.67945 -0.305054)
			(stroke
				(width 0.1)
				(type default)
			)
			(layer "F.Fab")
		)
		(pad "1" smd circle
			(at -0.40005 0 90)
			(size 0 0)
			(layers "F.Cu" "F.Mask" "F.Paste")
			(net "OCP_V3_2_P3V3_P12V_ADC_R_ALERT")
		)
		(pad "2" smd circle
			(at 0.40005 0 90)
			(size 0 0)
			(layers "F.Cu" "F.Mask" "F.Paste")
			(net "OCP_V3_2_P3V3_P12V_ADC_ALERT")
		)
	)
	(footprint ""
		(layer "F.Cu")
		(at 78.65237 -182.585106 90)
		(property "Reference" "PC262_1"
			(at 0 0 90)
			(layer "F.SilkS")
			(hide yes)
			(effects
				(font
					(size 1.27 1.27)
				)
			)
		)
		(property "Value" ""
			(at 0 0 90)
			(layer "F.Fab")
			(effects
				(font
					(size 1.27 1.27)
				)
			)
		)
		(duplicate_pad_numbers_are_jumpers no)
		(fp_line
			(start 0.7874 -0.4064)
			(end 0.7874 0.4064)
			(stroke
				(width 0.1524)
				(type default)
			)
			(layer "F.SilkS")
		)
		(fp_line
			(start -0.7874 -0.4064)
			(end 0.7874 -0.4064)
			(stroke
				(width 0.1524)
				(type default)
			)
			(layer "F.SilkS")
		)
		(fp_line
			(start 0.7874 0.4064)
			(end -0.7874 0.4064)
			(stroke
				(width 0.1524)
				(type default)
			)
			(layer "F.SilkS")
		)
		(fp_line
			(start -0.7874 0.4064)
			(end -0.7874 -0.4064)
			(stroke
				(width 0.1524)
				(type default)
			)
			(layer "F.SilkS")
		)
		(fp_line
			(start -0.12065 -0.305054)
			(end -0.12065 -0.2794)
			(stroke
				(width 0.1)
				(type default)
			)
			(layer "F.Fab")
		)
		(fp_line
			(start -0.67945 -0.305054)
			(end -0.12065 -0.305054)
			(stroke
				(width 0.1)
				(type default)
			)
			(layer "F.Fab")
		)
		(fp_line
			(start 0.67945 -0.3048)
			(end 0.67945 0.3048)
			(stroke
				(width 0.1)
				(type default)
			)
			(layer "F.Fab")
		)
		(fp_line
			(start 0.12065 -0.3048)
			(end 0.67945 -0.3048)
			(stroke
				(width 0.1)
				(type default)
			)
			(layer "F.Fab")
		)
		(fp_line
			(start 0.12065 -0.2794)
			(end 0.12065 -0.3048)
			(stroke
				(width 0.1)
				(type default)
			)
			(layer "F.Fab")
		)
		(fp_line
			(start -0.12065 -0.2794)
			(end 0.12065 -0.2794)
			(stroke
				(width 0.1)
				(type default)
			)
			(layer "F.Fab")
		)
		(fp_line
			(start 0.120396 0.2794)
			(end -0.12065 0.2794)
			(stroke
				(width 0.1)
				(type default)
			)
			(layer "F.Fab")
		)
		(fp_line
			(start -0.12065 0.2794)
			(end -0.12065 0.3048)
			(stroke
				(width 0.1)
				(type default)
			)
			(layer "F.Fab")
		)
		(fp_line
			(start 0.67945 0.3048)
			(end 0.120396 0.3048)
			(stroke
				(width 0.1)
				(type default)
			)
			(layer "F.Fab")
		)
		(fp_line
			(start 0.120396 0.3048)
			(end 0.120396 0.2794)
			(stroke
				(width 0.1)
				(type default)
			)
			(layer "F.Fab")
		)
		(fp_line
			(start -0.12065 0.3048)
			(end -0.67945 0.3048)
			(stroke
				(width 0.1)
				(type default)
			)
			(layer "F.Fab")
		)
		(fp_line
			(start -0.67945 0.3048)
			(end -0.67945 -0.305054)
			(stroke
				(width 0.1)
				(type default)
			)
			(layer "F.Fab")
		)
		(pad "1" smd circle
			(at -0.40005 0 90)
			(size 0 0)
			(layers "F.Cu" "F.Mask" "F.Paste")
			(net "SW_P12V_AUX_PVDDCR_CPU0_P1_FLT")
		)
		(pad "2" smd circle
			(at 0.40005 0 90)
			(size 0 0)
			(layers "F.Cu" "F.Mask" "F.Paste")
			(net "GND")
		)
	)
	(footprint ""
		(layer "F.Cu")
		(at 22.036278 -436.964074)
		(property "Reference" "R3522"
			(at 0 0 0)
			(layer "F.SilkS")
			(hide yes)
			(effects
				(font
					(size 1.27 1.27)
				)
			)
		)
		(property "Value" ""
			(at 0 0 0)
			(layer "F.Fab")
			(effects
				(font
					(size 1.27 1.27)
				)
			)
		)
		(duplicate_pad_numbers_are_jumpers no)
		(fp_line
			(start -0.7874 -0.4064)
			(end 0.7874 -0.4064)
			(stroke
				(width 0.1524)
				(type default)
			)
			(layer "F.SilkS")
		)
		(fp_line
			(start -0.7874 0.4064)
			(end -0.7874 -0.4064)
			(stroke
				(width 0.1524)
				(type default)
			)
			(layer "F.SilkS")
		)
		(fp_line
			(start 0.7874 -0.4064)
			(end 0.7874 0.4064)
			(stroke
				(width 0.1524)
				(type default)
			)
			(layer "F.SilkS")
		)
		(fp_line
			(start 0.7874 0.4064)
			(end -0.7874 0.4064)
			(stroke
				(width 0.1524)
				(type default)
			)
			(layer "F.SilkS")
		)
		(fp_line
			(start -0.67945 -0.305054)
			(end -0.12065 -0.305054)
			(stroke
				(width 0.1)
				(type default)
			)
			(layer "F.Fab")
		)
		(fp_line
			(start -0.67945 0.3048)
			(end -0.67945 -0.305054)
			(stroke
				(width 0.1)
				(type default)
			)
			(layer "F.Fab")
		)
		(fp_line
			(start -0.12065 -0.305054)
			(end -0.12065 -0.2794)
			(stroke
				(width 0.1)
				(type default)
			)
			(layer "F.Fab")
		)
		(fp_line
			(start -0.12065 -0.2794)
			(end 0.12065 -0.2794)
			(stroke
				(width 0.1)
				(type default)
			)
			(layer "F.Fab")
		)
		(fp_line
			(start -0.12065 0.2794)
			(end -0.12065 0.3048)
			(stroke
				(width 0.1)
				(type default)
			)
			(layer "F.Fab")
		)
		(fp_line
			(start -0.12065 0.3048)
			(end -0.67945 0.3048)
			(stroke
				(width 0.1)
				(type default)
			)
			(layer "F.Fab")
		)
		(fp_line
			(start 0.120396 0.2794)
			(end -0.12065 0.2794)
			(stroke
				(width 0.1)
				(type default)
			)
			(layer "F.Fab")
		)
		(fp_line
			(start 0.120396 0.3048)
			(end 0.120396 0.2794)
			(stroke
				(width 0.1)
				(type default)
			)
			(layer "F.Fab")
		)
		(fp_line
			(start 0.12065 -0.3048)
			(end 0.67945 -0.3048)
			(stroke
				(width 0.1)
				(type default)
			)
			(layer "F.Fab")
		)
		(fp_line
			(start 0.12065 -0.2794)
			(end 0.12065 -0.3048)
			(stroke
				(width 0.1)
				(type default)
			)
			(layer "F.Fab")
		)
		(fp_line
			(start 0.67945 -0.3048)
			(end 0.67945 0.3048)
			(stroke
				(width 0.1)
				(type default)
			)
			(layer "F.Fab")
		)
		(fp_line
			(start 0.67945 0.3048)
			(end 0.120396 0.3048)
			(stroke
				(width 0.1)
				(type default)
			)
			(layer "F.Fab")
		)
		(pad "1" smd circle
			(at -0.40005 0)
			(size 0 0)
			(layers "F.Cu" "F.Mask" "F.Paste")
			(net "P3V3_AUX")
		)
		(pad "2" smd circle
			(at 0.40005 0)
			(size 0 0)
			(layers "F.Cu" "F.Mask" "F.Paste")
			(net "SMB_2_BMC_GPU_BUF_R_SDA")
		)
	)
	(footprint ""
		(layer "F.Cu")
		(at 163.383976 -129.549652)
		(property "Reference" "Q1"
			(at -2.297176 -2.115566 0)
			(unlocked yes)
			(layer "F.SilkS")
			(effects
				(font
					(size 0.7874 0.5842)
					(thickness 0.1524)
				)
				(justify left)
			)
		)
		(property "Value" ""
			(at 0 0 0)
			(layer "F.Fab")
			(effects
				(font
					(size 1.27 1.27)
				)
			)
		)
		(duplicate_pad_numbers_are_jumpers no)
		(fp_line
			(start -1.332738 -1.100074)
			(end -0.4826 -1.100074)
			(stroke
				(width 0.1524)
				(type default)
			)
			(layer "F.SilkS")
		)
		(fp_line
			(start -1.332738 1.100074)
			(end -1.332738 -1.100074)
			(stroke
				(width 0.1524)
				(type default)
			)
			(layer "F.SilkS")
		)
		(fp_line
			(start -0.4826 -1.100074)
			(end 0 -0.541274)
			(stroke
				(width 0.1524)
				(type default)
			)
			(layer "F.SilkS")
		)
		(fp_line
			(start 0 -0.541274)
			(end 0.4826 -1.100074)
			(stroke
				(width 0.1524)
				(type default)
			)
			(layer "F.SilkS")
		)
		(fp_line
			(start 0.4826 -1.100074)
			(end 1.332738 -1.100074)
			(stroke
				(width 0.1524)
				(type default)
			)
			(layer "F.SilkS")
		)
		(fp_line
			(start 1.332738 -1.100074)
			(end 1.332738 1.100074)
			(stroke
				(width 0.1524)
				(type default)
			)
			(layer "F.SilkS")
		)
		(fp_line
			(start 1.332738 1.100074)
			(end -1.332738 1.100074)
			(stroke
				(width 0.1524)
				(type default)
			)
			(layer "F.SilkS")
		)
		(fp_poly
			(pts
				(xy -2.72542 -0.998982) (xy -2.446782 -1.64338) (xy -1.94183 -1.042416)
			)
			(stroke
				(width 0)
				(type default)
			)
			(fill yes)
			(layer "F.SilkS")
		)
		(fp_line
			(start -0.674878 -1.100074)
			(end 0.674878 -1.100074)
			(stroke
				(width 0.1)
				(type default)
			)
			(layer "F.Fab")
		)
		(fp_line
			(start -0.674878 1.100074)
			(end -0.674878 -1.100074)
			(stroke
				(width 0.1)
				(type default)
			)
			(layer "F.Fab")
		)
		(fp_line
			(start 0.674878 -1.100074)
			(end 0.674878 1.100074)
			(stroke
				(width 0.1)
				(type default)
			)
			(layer "F.Fab")
		)
		(fp_line
			(start 0.674878 1.100074)
			(end -0.674878 1.100074)
			(stroke
				(width 0.1)
				(type default)
			)
			(layer "F.Fab")
		)
		(fp_poly
			(pts
				(xy -2.2352 -0.298958) (xy -2.2352 -1.001014) (xy -1.533144 -0.649986)
			)
			(stroke
				(width 0)
				(type default)
			)
			(fill yes)
			(layer "F.Fab")
		)
		(pad "1" smd rect
			(at -0.94996 -0.649986 90)
			(size 0.4318 0.508)
			(layers "F.Cu" "F.Mask" "F.Paste")
			(net "GND")
		)
		(pad "2" smd rect
			(at -0.94996 0 90)
			(size 0.4318 0.508)
			(layers "F.Cu" "F.Mask" "F.Paste")
			(net "PWRGD_P5V_R1")
		)
		(pad "3" smd rect
			(at -0.94996 0.649986 90)
			(size 0.4318 0.508)
			(layers "F.Cu" "F.Mask" "F.Paste")
			(net "PWRGD_P5V_R2")
		)
		(pad "4" smd rect
			(at 0.94996 0.649986 90)
			(size 0.4318 0.508)
			(layers "F.Cu" "F.Mask" "F.Paste")
			(net "GND")
		)
		(pad "5" smd rect
			(at 0.94996 0 90)
			(size 0.4318 0.508)
			(layers "F.Cu" "F.Mask" "F.Paste")
			(net "PWRGD_P5V_N")
		)
		(pad "6" smd rect
			(at 0.94996 -0.649986 90)
			(size 0.4318 0.508)
			(layers "F.Cu" "F.Mask" "F.Paste")
			(net "PWRGD_P5V_R_N")
		)
	)
	(footprint ""
		(layer "F.Cu")
		(at 298.967144 -385.23926 180)
		(property "Reference" "C930"
			(at 0 0 180)
			(layer "F.SilkS")
			(hide yes)
			(effects
				(font
					(size 1.27 1.27)
				)
			)
		)
		(property "Value" ""
			(at 0 0 180)
			(layer "F.Fab")
			(effects
				(font
					(size 1.27 1.27)
				)
			)
		)
		(duplicate_pad_numbers_are_jumpers no)
		(fp_line
			(start 0.299974 0.150114)
			(end -0.299974 0.150114)
			(stroke
				(width 0.1)
				(type default)
			)
			(layer "F.Fab")
		)
		(fp_line
			(start 0.299974 -0.150114)
			(end 0.299974 0.150114)
			(stroke
				(width 0.1)
				(type default)
			)
			(layer "F.Fab")
		)
		(fp_line
			(start -0.299974 0.150114)
			(end -0.299974 -0.150114)
			(stroke
				(width 0.1)
				(type default)
			)
			(layer "F.Fab")
		)
		(fp_line
			(start -0.299974 -0.150114)
			(end 0.299974 -0.150114)
			(stroke
				(width 0.1)
				(type default)
			)
			(layer "F.Fab")
		)
		(pad "1" smd rect
			(at -0.2667 0 180)
			(size 0.3048 0.381)
			(layers "F.Cu" "F.Mask" "F.Paste")
			(net "P5E_CPU0_P0_TX_C_DN<1>")
		)
		(pad "2" smd rect
			(at 0.2667 0 180)
			(size 0.3048 0.381)
			(layers "F.Cu" "F.Mask" "F.Paste")
			(net "P5E_CPU0_P0_TX_DN<1>")
		)
	)
	(footprint ""
		(layer "F.Cu")
		(at 30.386528 -351.372932 -90)
		(property "Reference" "PC630"
			(at 0 0 270)
			(layer "F.SilkS")
			(hide yes)
			(effects
				(font
					(size 1.27 1.27)
				)
			)
		)
		(property "Value" ""
			(at 0 0 270)
			(layer "F.Fab")
			(effects
				(font
					(size 1.27 1.27)
				)
			)
		)
		(duplicate_pad_numbers_are_jumpers no)
		(fp_line
			(start -0.7874 0.4064)
			(end -0.7874 -0.4064)
			(stroke
				(width 0.1524)
				(type default)
			)
			(layer "F.SilkS")
		)
		(fp_line
			(start 0.7874 0.4064)
			(end -0.7874 0.4064)
			(stroke
				(width 0.1524)
				(type default)
			)
			(layer "F.SilkS")
		)
		(fp_line
			(start -0.7874 -0.4064)
			(end 0.7874 -0.4064)
			(stroke
				(width 0.1524)
				(type default)
			)
			(layer "F.SilkS")
		)
		(fp_line
			(start 0.7874 -0.4064)
			(end 0.7874 0.4064)
			(stroke
				(width 0.1524)
				(type default)
			)
			(layer "F.SilkS")
		)
		(fp_line
			(start -0.67945 0.3048)
			(end -0.67945 -0.305054)
			(stroke
				(width 0.1)
				(type default)
			)
			(layer "F.Fab")
		)
		(fp_line
			(start -0.12065 0.3048)
			(end -0.67945 0.3048)
			(stroke
				(width 0.1)
				(type default)
			)
			(layer "F.Fab")
		)
		(fp_line
			(start 0.120396 0.3048)
			(end 0.120396 0.2794)
			(stroke
				(width 0.1)
				(type default)
			)
			(layer "F.Fab")
		)
		(fp_line
			(start 0.67945 0.3048)
			(end 0.120396 0.3048)
			(stroke
				(width 0.1)
				(type default)
			)
			(layer "F.Fab")
		)
		(fp_line
			(start -0.12065 0.2794)
			(end -0.12065 0.3048)
			(stroke
				(width 0.1)
				(type default)
			)
			(layer "F.Fab")
		)
		(fp_line
			(start 0.120396 0.2794)
			(end -0.12065 0.2794)
			(stroke
				(width 0.1)
				(type default)
			)
			(layer "F.Fab")
		)
		(fp_line
			(start -0.12065 -0.2794)
			(end 0.12065 -0.2794)
			(stroke
				(width 0.1)
				(type default)
			)
			(layer "F.Fab")
		)
		(fp_line
			(start 0.12065 -0.2794)
			(end 0.12065 -0.3048)
			(stroke
				(width 0.1)
				(type default)
			)
			(layer "F.Fab")
		)
		(fp_line
			(start 0.12065 -0.3048)
			(end 0.67945 -0.3048)
			(stroke
				(width 0.1)
				(type default)
			)
			(layer "F.Fab")
		)
		(fp_line
			(start 0.67945 -0.3048)
			(end 0.67945 0.3048)
			(stroke
				(width 0.1)
				(type default)
			)
			(layer "F.Fab")
		)
		(fp_line
			(start -0.67945 -0.305054)
			(end -0.12065 -0.305054)
			(stroke
				(width 0.1)
				(type default)
			)
			(layer "F.Fab")
		)
		(fp_line
			(start -0.12065 -0.305054)
			(end -0.12065 -0.2794)
			(stroke
				(width 0.1)
				(type default)
			)
			(layer "F.Fab")
		)
		(pad "1" smd circle
			(at -0.40005 0 270)
			(size 0 0)
			(layers "F.Cu" "F.Mask" "F.Paste")
			(net "SW_PVDDIO_P1_BOOT4_R")
		)
		(pad "2" smd circle
			(at 0.40005 0 270)
			(size 0 0)
			(layers "F.Cu" "F.Mask" "F.Paste")
			(net "SW_PVDDIO_P1_BOOTR4")
		)
	)
)
